(kicad_pcb
	(version 20260206)
	(generator "pcbnew")
	(generator_version "10.0")
	(general
		(thickness 1.6)
		(legacy_teardrops no)
	)
	(paper "A4")
	(title_block
		(title "Bryce Canyon_F.DPB_16315-1-OCP.brd")
		(comment 1 "Bryce Canyon / footprints 1635-1640 of 2223")
	)
	(layers
		(0 "F.Cu" signal "TOP")
		(4 "In1.Cu" signal "L2GND")
		(6 "In2.Cu" signal "L3")
		(8 "In3.Cu" signal "L4GND")
		(10 "In4.Cu" signal "L5")
		(12 "In5.Cu" signal "L6VCC")
		(14 "In6.Cu" signal "L7VCC")
		(16 "In7.Cu" signal "L8")
		(18 "In8.Cu" signal "L9GND")
		(20 "In9.Cu" signal "L10")
		(22 "In10.Cu" signal "L11GND")
		(2 "B.Cu" signal "BOTTOM")
		(9 "F.Adhes" user "F.Adhesive")
		(11 "B.Adhes" user "B.Adhesive")
		(13 "F.Paste" user "Package Geometry/Pastemask Top")
		(15 "B.Paste" user "Package Geometry/Pastemask Bottom")
		(5 "F.SilkS" user "Ref Des/Silkscreen Top")
		(7 "B.SilkS" user "Ref Des/Silkscreen Bottom")
		(1 "F.Mask" user "Board Geometry/Soldermask Top")
		(3 "B.Mask" user "Board Geometry/Soldermask Bottom")
		(17 "Dwgs.User" user "User.Drawings")
		(19 "Cmts.User" user "User.Comments")
		(21 "Eco1.User" user "User.Eco1")
		(23 "Eco2.User" user "User.Eco2")
		(25 "Edge.Cuts" user "Board Geometry/Outline")
		(27 "Margin" user)
		(31 "F.CrtYd" user "Package Geometry/Place Bound Top")
		(29 "B.CrtYd" user "Package Geometry/Place Bound Bottom")
		(35 "F.Fab" user "Ref Des/Assembly Top")
		(33 "B.Fab" user "Ref Des/Assembly Bottom")
	)
	(footprint ""
		(layer "F.Cu")
		(at 145.106898 -64.683894 90)
		(property "Reference" "R775"
			(at 0 0 90)
			(layer "F.SilkS")
			(hide yes)
			(effects
				(font
					(size 1.27 1.27)
				)
			)
		)
		(property "Value" "2R6F-GP"
			(at -0.0508 -4.8514 90)
			(unlocked yes)
			(layer "F.Fab")
			(hide yes)
			(effects
				(font
					(size 1.016 1.016)
					(thickness 0.1524)
				)
			)
		)
		(property "Device Type" "R1206H26"
			(at 0 -6.3754 90)
			(unlocked yes)
			(layer "F.Fab")
			(hide yes)
			(effects
				(font
					(size 1.016 1.016)
					(thickness 0.1524)
				)
			)
		)
		(duplicate_pad_numbers_are_jumpers no)
		(fp_line
			(start 1.016 -2.2352)
			(end 1.016 2.2352)
			(stroke
				(width 0.1524)
				(type default)
			)
			(layer "F.SilkS")
		)
		(fp_line
			(start -1.016 -2.2352)
			(end 1.016 -2.2352)
			(stroke
				(width 0.1524)
				(type default)
			)
			(layer "F.SilkS")
		)
		(fp_line
			(start 1.016 2.2352)
			(end -1.016 2.2352)
			(stroke
				(width 0.1524)
				(type default)
			)
			(layer "F.SilkS")
		)
		(fp_line
			(start -1.016 2.2352)
			(end -1.016 -2.2352)
			(stroke
				(width 0.1524)
				(type default)
			)
			(layer "F.SilkS")
		)
		(fp_rect
			(start -1.0922 2.3114)
			(end 1.0922 -2.3114)
			(stroke
				(width 0)
				(type default)
			)
			(fill no)
			(layer "F.CrtYd")
		)
		(fp_poly
			(pts
				(xy -1.0922 -2.3114) (xy 1.0922 -2.3114) (xy 1.0922 2.3114) (xy -1.0922 2.3114)
			)
			(stroke
				(width 0)
				(type default)
			)
			(fill no)
			(layer "F.Fab")
		)
		(pad "1" smd rect
			(at 0 -1.397 90)
			(size 1.651 1.27)
			(layers "F.Cu" "F.Mask" "F.Paste")
			(net "P12V_HDD28")
		)
		(pad "2" smd rect
			(at 0 1.397 90)
			(size 1.651 1.27)
			(layers "F.Cu" "F.Mask" "F.Paste")
			(net "12V_PRE_28")
		)
	)
	(footprint ""
		(layer "F.Cu")
		(at 466.164168 -127.75692 180)
		(property "Reference" "Q286"
			(at 0 0 180)
			(layer "F.SilkS")
			(hide yes)
			(effects
				(font
					(size 1.27 1.27)
				)
			)
		)
		(property "Value" "SSM3K324R-GP"
			(at 0.127 -8.9662 180)
			(unlocked yes)
			(layer "F.Fab")
			(hide yes)
			(effects
				(font
					(size 1.016 1.016)
					(thickness 0.1524)
				)
			)
		)
		(property "Device Type" "SOT23DGS2D4H35"
			(at 0.127 -10.4902 180)
			(unlocked yes)
			(layer "F.Fab")
			(hide yes)
			(effects
				(font
					(size 1.016 1.016)
					(thickness 0.1524)
				)
			)
		)
		(duplicate_pad_numbers_are_jumpers no)
		(fp_line
			(start 1.651 1.778)
			(end 1.651 -1.778)
			(stroke
				(width 0.1524)
				(type default)
			)
			(layer "F.SilkS")
		)
		(fp_line
			(start 1.651 -1.778)
			(end -1.651 -1.778)
			(stroke
				(width 0.1524)
				(type default)
			)
			(layer "F.SilkS")
		)
		(fp_line
			(start -1.651 1.778)
			(end 1.651 1.778)
			(stroke
				(width 0.1524)
				(type default)
			)
			(layer "F.SilkS")
		)
		(fp_line
			(start -1.651 -1.778)
			(end -1.651 1.778)
			(stroke
				(width 0.1524)
				(type default)
			)
			(layer "F.SilkS")
		)
		(fp_poly
			(pts
				(xy -1.778 1.8796) (xy -1.778 -1.8796) (xy 1.778 -1.8796) (xy 1.778 1.8796)
			)
			(stroke
				(width 0)
				(type default)
			)
			(fill no)
			(layer "F.CrtYd")
		)
		(fp_poly
			(pts
				(xy -1.778 1.8796) (xy -1.778 -1.8796) (xy 1.778 -1.8796) (xy 1.778 1.8796)
			)
			(stroke
				(width 0)
				(type default)
			)
			(fill no)
			(layer "F.Fab")
		)
		(pad "D" smd custom
			(at 0 -0.9525 180)
			(size 0.1905 0.1905)
			(layers "F.Cu" "F.Mask" "F.Paste")
			(net "DRV_ACT_23_N")
			(options
				(clearance outline)
				(anchor circle)
			)
			(primitives
				(gr_poly
					(pts
						(arc
							(start -0.1778 0.5715)
							(mid -0.321484 0.511984)
							(end -0.381 0.3683)
						)
						(arc
							(start -0.381 -0.3683)
							(mid -0.321484 -0.511984)
							(end -0.1778 -0.5715)
						)
						(arc
							(start 0.1778 -0.5715)
							(mid 0.321484 -0.511984)
							(end 0.381 -0.3683)
						)
						(arc
							(start 0.381 0.3683)
							(mid 0.321484 0.511984)
							(end 0.1778 0.5715)
						)
					)
					(width 0)
					(fill yes)
				)
			)
		)
		(pad "G" smd custom
			(at -0.98425 0.9525 180)
			(size 0.1905 0.1905)
			(layers "F.Cu" "F.Mask" "F.Paste")
			(net "DRIVE_A_23_ACT")
			(options
				(clearance outline)
				(anchor circle)
			)
			(primitives
				(gr_poly
					(pts
						(arc
							(start -0.1778 0.5715)
							(mid -0.321484 0.511984)
							(end -0.381 0.3683)
						)
						(arc
							(start -0.381 -0.3683)
							(mid -0.321484 -0.511984)
							(end -0.1778 -0.5715)
						)
						(arc
							(start 0.1778 -0.5715)
							(mid 0.321484 -0.511984)
							(end 0.381 -0.3683)
						)
						(arc
							(start 0.381 0.3683)
							(mid 0.321484 0.511984)
							(end 0.1778 0.5715)
						)
					)
					(width 0)
					(fill yes)
				)
			)
		)
		(pad "S" smd custom
			(at 0.98425 0.9525 180)
			(size 0.1905 0.1905)
			(layers "F.Cu" "F.Mask" "F.Paste")
			(net "GND")
			(options
				(clearance outline)
				(anchor circle)
			)
			(primitives
				(gr_poly
					(pts
						(arc
							(start -0.1778 0.5715)
							(mid -0.321484 0.511984)
							(end -0.381 0.3683)
						)
						(arc
							(start -0.381 -0.3683)
							(mid -0.321484 -0.511984)
							(end -0.1778 -0.5715)
						)
						(arc
							(start 0.1778 -0.5715)
							(mid 0.321484 -0.511984)
							(end 0.381 -0.3683)
						)
						(arc
							(start 0.381 0.3683)
							(mid 0.321484 0.511984)
							(end 0.1778 0.5715)
						)
					)
					(width 0)
					(fill yes)
				)
			)
		)
	)
	(footprint ""
		(layer "F.Cu")
		(at 225.245168 -357.991156)
		(property "Reference" "R380"
			(at 0 0 0)
			(layer "F.SilkS")
			(hide yes)
			(effects
				(font
					(size 1.27 1.27)
				)
			)
		)
		(property "Value" "100KR2F-L1-GP"
			(at 0.064008 -3.993896 0)
			(unlocked yes)
			(layer "F.Fab")
			(hide yes)
			(effects
				(font
					(size 1.016 1.016)
					(thickness 0.1524)
				)
			)
		)
		(property "Device Type" "R402H16"
			(at 0.064008 -5.517896 0)
			(unlocked yes)
			(layer "F.Fab")
			(hide yes)
			(effects
				(font
					(size 1.016 1.016)
					(thickness 0.1524)
				)
			)
		)
		(duplicate_pad_numbers_are_jumpers no)
		(fp_line
			(start -0.508 -0.9398)
			(end -0.508 0.9398)
			(stroke
				(width 0.1524)
				(type default)
			)
			(layer "F.SilkS")
		)
		(fp_line
			(start 0.508 -0.9398)
			(end -0.508 -0.9398)
			(stroke
				(width 0.1524)
				(type default)
			)
			(layer "F.SilkS")
		)
		(fp_rect
			(start -0.508 0.9398)
			(end 0.508 -0.9398)
			(stroke
				(width 0)
				(type default)
			)
			(fill no)
			(layer "F.CrtYd")
		)
		(fp_rect
			(start -0.508 0.9398)
			(end 0.508 -0.9398)
			(stroke
				(width 0)
				(type default)
			)
			(fill no)
			(layer "F.Fab")
		)
		(pad "1" smd custom
			(at 0 -0.4445)
			(size 0.1397 0.1397)
			(layers "F.Cu" "F.Mask" "F.Paste")
			(net "P3V3_STBY_A")
			(options
				(clearance outline)
				(anchor circle)
			)
			(primitives
				(gr_poly
					(pts
						(arc
							(start -0.1778 -0.2794)
							(mid -0.249642 -0.249642)
							(end -0.2794 -0.1778)
						)
						(arc
							(start -0.2794 0.1778)
							(mid -0.249642 0.249642)
							(end -0.1778 0.2794)
						)
						(arc
							(start 0.1778 0.2794)
							(mid 0.249642 0.249642)
							(end 0.2794 0.1778)
						)
						(arc
							(start 0.2794 -0.1778)
							(mid 0.249642 -0.249642)
							(end 0.1778 -0.2794)
						)
					)
					(width 0)
					(fill yes)
				)
			)
		)
		(pad "2" smd custom
			(at 0 0.4445)
			(size 0.1397 0.1397)
			(layers "F.Cu" "F.Mask" "F.Paste")
			(net "SCC_A_INS_N")
			(options
				(clearance outline)
				(anchor circle)
			)
			(primitives
				(gr_poly
					(pts
						(arc
							(start -0.1778 -0.2794)
							(mid -0.249642 -0.249642)
							(end -0.2794 -0.1778)
						)
						(arc
							(start -0.2794 0.1778)
							(mid -0.249642 0.249642)
							(end -0.1778 0.2794)
						)
						(arc
							(start 0.1778 0.2794)
							(mid 0.249642 0.249642)
							(end 0.2794 0.1778)
						)
						(arc
							(start 0.2794 -0.1778)
							(mid 0.249642 -0.249642)
							(end 0.1778 -0.2794)
						)
					)
					(width 0)
					(fill yes)
				)
			)
		)
	)
	(footprint ""
		(layer "F.Cu")
		(at 77.942948 -283.482542 -90)
		(property "Reference" "R191"
			(at 0 0 270)
			(layer "F.SilkS")
			(hide yes)
			(effects
				(font
					(size 1.27 1.27)
				)
			)
		)
		(property "Value" "300KR2F-GP"
			(at 0.064008 -3.993896 270)
			(unlocked yes)
			(layer "F.Fab")
			(hide yes)
			(effects
				(font
					(size 1.016 1.016)
					(thickness 0.1524)
				)
			)
		)
		(property "Device Type" "R402H16"
			(at 0.064008 -5.517896 270)
			(unlocked yes)
			(layer "F.Fab")
			(hide yes)
			(effects
				(font
					(size 1.016 1.016)
					(thickness 0.1524)
				)
			)
		)
		(duplicate_pad_numbers_are_jumpers no)
		(fp_line
			(start -0.508 -0.9398)
			(end -0.508 0.9398)
			(stroke
				(width 0.1524)
				(type default)
			)
			(layer "F.SilkS")
		)
		(fp_line
			(start 0.508 -0.9398)
			(end -0.508 -0.9398)
			(stroke
				(width 0.1524)
				(type default)
			)
			(layer "F.SilkS")
		)
		(fp_rect
			(start -0.508 0.9398)
			(end 0.508 -0.9398)
			(stroke
				(width 0)
				(type default)
			)
			(fill no)
			(layer "F.CrtYd")
		)
		(fp_rect
			(start -0.508 0.9398)
			(end 0.508 -0.9398)
			(stroke
				(width 0)
				(type default)
			)
			(fill no)
			(layer "F.Fab")
		)
		(pad "1" smd custom
			(at 0 -0.4445 270)
			(size 0.1397 0.1397)
			(layers "F.Cu" "F.Mask" "F.Paste")
			(net "SW_HDD_N2")
			(options
				(clearance outline)
				(anchor circle)
			)
			(primitives
				(gr_poly
					(pts
						(arc
							(start -0.1778 -0.2794)
							(mid -0.249642 -0.249642)
							(end -0.2794 -0.1778)
						)
						(arc
							(start -0.2794 0.1778)
							(mid -0.249642 0.249642)
							(end -0.1778 0.2794)
						)
						(arc
							(start 0.1778 0.2794)
							(mid 0.249642 0.249642)
							(end 0.2794 0.1778)
						)
						(arc
							(start 0.2794 -0.1778)
							(mid 0.249642 -0.249642)
							(end 0.1778 -0.2794)
						)
					)
					(width 0)
					(fill yes)
				)
			)
		)
		(pad "2" smd custom
			(at 0 0.4445 270)
			(size 0.1397 0.1397)
			(layers "F.Cu" "F.Mask" "F.Paste")
			(net "P12V_A")
			(options
				(clearance outline)
				(anchor circle)
			)
			(primitives
				(gr_poly
					(pts
						(arc
							(start -0.1778 -0.2794)
							(mid -0.249642 -0.249642)
							(end -0.2794 -0.1778)
						)
						(arc
							(start -0.2794 0.1778)
							(mid -0.249642 0.249642)
							(end -0.1778 0.2794)
						)
						(arc
							(start 0.1778 0.2794)
							(mid 0.249642 0.249642)
							(end 0.2794 0.1778)
						)
						(arc
							(start 0.2794 -0.1778)
							(mid 0.249642 -0.249642)
							(end 0.1778 -0.2794)
						)
					)
					(width 0)
					(fill yes)
				)
			)
		)
	)
	(footprint ""
		(layer "F.Cu")
		(at 450.9389 -47.749968 -90)
		(property "Reference" "VIA30"
			(at 0 0 270)
			(layer "F.SilkS")
			(hide yes)
			(effects
				(font
					(size 1.27 1.27)
				)
			)
		)
		(property "Value" "100OHM-8L-1D6MM-L18L16-GP"
			(at -3.7211 -4.5085 270)
			(unlocked yes)
			(layer "F.Fab")
			(hide yes)
			(effects
				(font
					(size 1.016 1.016)
					(thickness 0.1524)
				)
			)
		)
		(property "Device Type" "VIA-PCIE-4P-394076"
			(at -3.7211 -6.0325 270)
			(unlocked yes)
			(layer "F.Fab")
			(hide yes)
			(effects
				(font
					(size 1.016 1.016)
					(thickness 0.1524)
				)
			)
		)
		(duplicate_pad_numbers_are_jumpers no)
		(fp_rect
			(start -1.9685 0.381)
			(end 1.9685 -0.381)
			(stroke
				(width 0)
				(type default)
			)
			(fill no)
			(layer "F.CrtYd")
		)
		(fp_rect
			(start -1.9685 0.381)
			(end 1.9685 -0.381)
			(stroke
				(width 0)
				(type default)
			)
			(fill no)
			(layer "F.Fab")
		)
		(pad "1" thru_hole circle
			(at -1.5875 0 270)
			(size 0.508 0.508)
			(drill 0.254)
			(layers "*.Cu" "*.Mask")
			(remove_unused_layers no)
			(net "GND")
			(clearance 0.127)
			(thermal_gap 0.127)
		)
		(pad "2" thru_hole circle
			(at -0.5715 0 270)
			(size 0.508 0.508)
			(drill 0.254)
			(layers "*.Cu" "*.Mask")
			(remove_unused_layers no)
			(net "PHY_DRV_A_TO_SCC_A_34_DP")
			(clearance 0.127)
			(thermal_gap 0.127)
		)
		(pad "3" thru_hole circle
			(at 0.5715 0 270)
			(size 0.508 0.508)
			(drill 0.254)
			(layers "*.Cu" "*.Mask")
			(remove_unused_layers no)
			(net "PHY_DRV_A_TO_SCC_A_34_DN")
			(clearance 0.127)
			(thermal_gap 0.127)
		)
		(pad "4" thru_hole circle
			(at 1.5875 0 270)
			(size 0.508 0.508)
			(drill 0.254)
			(layers "*.Cu" "*.Mask")
			(remove_unused_layers no)
			(net "GND")
			(clearance 0.127)
			(thermal_gap 0.127)
		)
	)
	(footprint ""
		(layer "F.Cu")
		(at 426.755052 -275.252942 -90)
		(property "Reference" "Q55"
			(at 0 0 270)
			(layer "F.SilkS")
			(hide yes)
			(effects
				(font
					(size 1.27 1.27)
				)
			)
		)
		(property "Value" "2N7002KDW-GP"
			(at -2.3622 -8.2042 270)
			(unlocked yes)
			(layer "F.Fab")
			(hide yes)
			(effects
				(font
					(size 1.016 1.016)
					(thickness 0.1524)
				)
			)
		)
		(property "Device Type" "SOT-363H44"
			(at -2.3622 -10.1092 270)
			(unlocked yes)
			(layer "F.Fab")
			(hide yes)
			(effects
				(font
					(size 1.016 1.016)
					(thickness 0.1524)
				)
			)
		)
		(duplicate_pad_numbers_are_jumpers no)
		(fp_line
			(start -1.4478 1.7018)
			(end 1.4478 1.7018)
			(stroke
				(width 0.1524)
				(type default)
			)
			(layer "F.SilkS")
		)
		(fp_line
			(start 1.4478 1.7018)
			(end 1.4478 -1.7018)
			(stroke
				(width 0.1524)
				(type default)
			)
			(layer "F.SilkS")
		)
		(fp_line
			(start -1.27 1.524)
			(end -1.27 0.6604)
			(stroke
				(width 0.4826)
				(type default)
			)
			(layer "F.SilkS")
		)
		(fp_line
			(start -1.4478 -1.7018)
			(end -1.4478 1.7018)
			(stroke
				(width 0.1524)
				(type default)
			)
			(layer "F.SilkS")
		)
		(fp_line
			(start 1.4478 -1.7018)
			(end -1.4478 -1.7018)
			(stroke
				(width 0.1524)
				(type default)
			)
			(layer "F.SilkS")
		)
		(fp_poly
			(pts
				(xy -1.524 -1.778) (xy 1.524 -1.778) (xy 1.524 1.778) (xy -1.524 1.778)
			)
			(stroke
				(width 0)
				(type default)
			)
			(fill no)
			(layer "F.CrtYd")
		)
		(fp_poly
			(pts
				(xy -1.524 -1.778) (xy 1.524 -1.778) (xy 1.524 1.778) (xy -1.524 1.778)
			)
			(stroke
				(width 0)
				(type default)
			)
			(fill no)
			(layer "F.Fab")
		)
		(pad "1" smd rect
			(at -0.65024 0.9398 270)
			(size 0.4064 1.016)
			(layers "F.Cu" "F.Mask" "F.Paste")
			(net "GND")
		)
		(pad "2" smd rect
			(at 0 0.9398 270)
			(size 0.4064 1.016)
			(layers "F.Cu" "F.Mask" "F.Paste")
			(net "SW_PWR_R_HDD9")
		)
		(pad "3" smd rect
			(at 0.65024 0.9398 270)
			(size 0.4064 1.016)
			(layers "F.Cu" "F.Mask" "F.Paste")
			(net "SW_HDD_P9")
		)
		(pad "4" smd rect
			(at 0.65024 -0.9398 270)
			(size 0.4064 1.016)
			(layers "F.Cu" "F.Mask" "F.Paste")
			(net "GND")
		)
		(pad "5" smd rect
			(at 0 -0.9398 270)
			(size 0.4064 1.016)
			(layers "F.Cu" "F.Mask" "F.Paste")
			(net "SW_HDD_G9")
		)
		(pad "6" smd rect
			(at -0.65024 -0.9398 270)
			(size 0.4064 1.016)
			(layers "F.Cu" "F.Mask" "F.Paste")
			(net "SW_HDD_R9")
		)
	)
)
